# BARRELEYE_G2-MB-PVT-X04-HW-BOM-X26_20180122_Final.xls.xlsx — Component Qual Tracker (bom)
|  |  |  |  |  |  |  |  | Part to be included on following build: |  |  |  |  |  |
| Item No. | Part Group | Single/Sole/Multi | Item Description | ODM P/N | Customer PN | Vendor | Vendor P/N | X00 Build | X01 Build | X02 Build | Qual Build | Qualification Target Date | Qualification Complete Date |
|  | VR Controllers |  |  |  |  | Vendor #1 |  |  |  |  |  |  |  |
|  |  |  |  |  |  | Vendor #2 |  |  |  |  |  |  |  |
|  | FETS |  |  |  |  | Vendor #1 |  |  |  |  |  |  |  |
|  |  |  |  |  |  | Vendor #2 |  |  |  |  |  |  |  |
|  | INDUCTORS |  |  |  |  | Vendor #1 |  |  |  |  |  |  |  |
|  |  |  |  |  |  | Vendor #2 |  |  |  |  |  |  |  |
|  | VREG CAPS |  |  |  |  | Vendor #1 |  |  |  |  |  |  |  |
|  |  |  |  |  |  | Vendor #2 |  |  |  |  |  |  |  |
|  | CRYSTALS |  |  |  |  | Vendor #1 |  |  |  |  |  |  |  |
|  |  |  |  |  |  | Vendor #2 |  |  |  |  |  |  |  |
|  | CONNECTORS |  |  |  |  | Vendor #1 |  |  |  |  |  |  |  |
|  |  |  |  |  |  | Vendor #2 |  |  |  |  |  |  |  |
|  | IC'S |  |  |  |  | Vendor #1 |  |  |  |  |  |  |  |
|  |  |  |  |  |  | Vendor #2 |  |  |  |  |  |  |  |
|  | MISC. |  |  |  |  | Vendor #1 |  |  |  |  |  |  |  |
|  | (HEATSINKS) |  |  |  |  | Vendor #2 |  |  |  |  |  |  |  |
